(kicad_pcb
	(version 20260206)
	(generator "pcbnew")
	(generator_version "10.0")
	(general
		(thickness 1.6)
		(legacy_teardrops no)
	)
	(paper "A4")
	(title_block
		(title "Wiwynn_Tioga_Pass_MB.brd")
		(comment 1 "Tioga Pass / footprints 1720-1726 of 4770")
	)
	(layers
		(0 "F.Cu" signal "TOP")
		(4 "In1.Cu" signal "L2GND")
		(6 "In2.Cu" signal "L3")
		(8 "In3.Cu" signal "L4GND")
		(10 "In4.Cu" signal "L5")
		(12 "In5.Cu" signal "L6GND")
		(14 "In6.Cu" signal "L7VCC")
		(16 "In7.Cu" signal "L8VCC")
		(18 "In8.Cu" signal "L9GND")
		(20 "In9.Cu" signal "L10")
		(22 "In10.Cu" signal "L11GND")
		(24 "In11.Cu" signal "L12")
		(26 "In12.Cu" signal "L13GND")
		(2 "B.Cu" signal "BOTTOM")
		(9 "F.Adhes" user "F.Adhesive")
		(11 "B.Adhes" user "B.Adhesive")
		(13 "F.Paste" user "Package Geometry/Pastemask Top")
		(15 "B.Paste" user "Package Geometry/Pastemask Bottom")
		(5 "F.SilkS" user "Ref Des/Silkscreen Top")
		(7 "B.SilkS" user "Ref Des/Silkscreen Bottom")
		(1 "F.Mask" user "Board Geometry/Soldermask Top")
		(3 "B.Mask" user "Board Geometry/Soldermask Bottom")
		(17 "Dwgs.User" user "User.Drawings")
		(19 "Cmts.User" user "User.Comments")
		(21 "Eco1.User" user "User.Eco1")
		(23 "Eco2.User" user "User.Eco2")
		(25 "Edge.Cuts" user "Board Geometry/Outline")
		(27 "Margin" user)
		(31 "F.CrtYd" user "Package Geometry/Place Bound Top")
		(29 "B.CrtYd" user "Package Geometry/Place Bound Bottom")
		(35 "F.Fab" user "Ref Des/Assembly Top")
		(33 "B.Fab" user "Ref Des/Assembly Bottom")
	)
	(footprint ""
		(layer "F.Cu")
		(at 429.895 -22.86 -90)
		(property "Reference" "R10W4"
			(at -0.8382 -0.67818 270)
			(unlocked yes)
			(layer "F.SilkS")
			(effects
				(font
					(size 0.4064 0.254)
					(thickness 0.1524)
				)
				(justify left)
			)
		)
		(property "Value" ""
			(at 0 0 270)
			(layer "F.Fab")
			(effects
				(font
					(size 1.27 1.27)
				)
			)
		)
		(duplicate_pad_numbers_are_jumpers no)
		(fp_poly
			(pts
				(xy -0.2794 -0.1016) (xy 0.2794 -0.1016) (xy 0.2794 0.9906) (xy -0.2794 0.9906)
			)
			(stroke
				(width 0)
				(type default)
			)
			(fill no)
			(layer "F.CrtYd")
		)
		(fp_line
			(start -0.2794 0.9906)
			(end 0.2794 0.9906)
			(stroke
				(width 0.1)
				(type default)
			)
			(layer "F.Fab")
		)
		(fp_line
			(start 0.2794 0.9906)
			(end 0.2794 -0.1016)
			(stroke
				(width 0.1)
				(type default)
			)
			(layer "F.Fab")
		)
		(fp_line
			(start -0.2794 -0.1016)
			(end -0.2794 0.9906)
			(stroke
				(width 0.1)
				(type default)
			)
			(layer "F.Fab")
		)
		(fp_line
			(start 0.2794 -0.1016)
			(end -0.2794 -0.1016)
			(stroke
				(width 0.1)
				(type default)
			)
			(layer "F.Fab")
		)
		(pad "1" smd rect
			(at 0 0 270)
			(size 0.508 0.508)
			(layers "F.Cu" "F.Mask" "F.Paste")
			(net "PUMP_PWM_OUT_BUF")
		)
		(pad "2" smd rect
			(at 0 0.889 270)
			(size 0.508 0.508)
			(layers "F.Cu" "F.Mask" "F.Paste")
			(net "PUMP_PWM_OUT_R")
		)
		(zone
			(layer "F.Cu")
			(hatch none 0.5)
			(connect_pads
				(clearance 0)
			)
			(min_thickness 0.25)
			(keepout
				(tracks not_allowed)
				(vias allowed)
				(pads allowed)
				(copperpour not_allowed)
				(footprints allowed)
			)
			(placement
				(enabled no)
				(sheetname "")
			)
			(fill
				(thermal_gap 0.5)
				(thermal_bridge_width 0.5)
				(island_removal_mode 0)
			)
			(polygon
				(pts
					(xy 429.26 -23.114) (xy 429.26 -22.606) (xy 429.641 -22.606) (xy 429.641 -23.114)
				)
			)
		)
		(zone
			(layer "F.Cu")
			(hatch none 0.5)
			(connect_pads
				(clearance 0)
			)
			(min_thickness 0.25)
			(keepout
				(tracks allowed)
				(vias not_allowed)
				(pads allowed)
				(copperpour not_allowed)
				(footprints allowed)
			)
			(placement
				(enabled no)
				(sheetname "")
			)
			(fill
				(thermal_gap 0.5)
				(thermal_bridge_width 0.5)
				(island_removal_mode 0)
			)
			(polygon
				(pts
					(xy 429.641 -23.114) (xy 429.641 -22.606) (xy 429.26 -22.606) (xy 429.26 -23.114)
				)
			)
		)
	)
	(footprint ""
		(layer "F.Cu")
		(at 341.6046 -127.4445 180)
		(property "Reference" "R7B16"
			(at 0 0 180)
			(layer "F.SilkS")
			(hide yes)
			(effects
				(font
					(size 1.27 1.27)
				)
			)
		)
		(property "Value" ""
			(at 0 0 180)
			(layer "F.Fab")
			(effects
				(font
					(size 1.27 1.27)
				)
			)
		)
		(duplicate_pad_numbers_are_jumpers no)
		(fp_poly
			(pts
				(xy -0.2794 -0.1016) (xy 0.2794 -0.1016) (xy 0.2794 0.9906) (xy -0.2794 0.9906)
			)
			(stroke
				(width 0)
				(type default)
			)
			(fill no)
			(layer "F.CrtYd")
		)
		(fp_line
			(start 0.2794 0.9906)
			(end 0.2794 -0.1016)
			(stroke
				(width 0.1)
				(type default)
			)
			(layer "F.Fab")
		)
		(fp_line
			(start 0.2794 -0.1016)
			(end -0.2794 -0.1016)
			(stroke
				(width 0.1)
				(type default)
			)
			(layer "F.Fab")
		)
		(fp_line
			(start -0.2794 0.9906)
			(end 0.2794 0.9906)
			(stroke
				(width 0.1)
				(type default)
			)
			(layer "F.Fab")
		)
		(fp_line
			(start -0.2794 -0.1016)
			(end -0.2794 0.9906)
			(stroke
				(width 0.1)
				(type default)
			)
			(layer "F.Fab")
		)
		(pad "1" smd rect
			(at 0 0 180)
			(size 0.508 0.508)
			(layers "F.Cu" "F.Mask" "F.Paste")
			(net "VR_COMP_RC_PVPP_DEF")
		)
		(pad "2" smd rect
			(at 0 0.889 180)
			(size 0.508 0.508)
			(layers "F.Cu" "F.Mask" "F.Paste")
			(net "VR_FB_PVPP_DEF")
		)
		(zone
			(layer "F.Cu")
			(hatch none 0.5)
			(connect_pads
				(clearance 0)
			)
			(min_thickness 0.25)
			(keepout
				(tracks not_allowed)
				(vias allowed)
				(pads allowed)
				(copperpour not_allowed)
				(footprints allowed)
			)
			(placement
				(enabled no)
				(sheetname "")
			)
			(fill
				(thermal_gap 0.5)
				(thermal_bridge_width 0.5)
				(island_removal_mode 0)
			)
			(polygon
				(pts
					(xy 341.8586 -128.0795) (xy 341.3506 -128.0795) (xy 341.3506 -127.6985) (xy 341.8586 -127.6985)
				)
			)
		)
		(zone
			(layer "F.Cu")
			(hatch none 0.5)
			(connect_pads
				(clearance 0)
			)
			(min_thickness 0.25)
			(keepout
				(tracks allowed)
				(vias not_allowed)
				(pads allowed)
				(copperpour not_allowed)
				(footprints allowed)
			)
			(placement
				(enabled no)
				(sheetname "")
			)
			(fill
				(thermal_gap 0.5)
				(thermal_bridge_width 0.5)
				(island_removal_mode 0)
			)
			(polygon
				(pts
					(xy 341.8586 -127.6985) (xy 341.3506 -127.6985) (xy 341.3506 -128.0795) (xy 341.8586 -128.0795)
				)
			)
		)
	)
	(footprint ""
		(layer "F.Cu")
		(at -2.856484 -149.29231 90)
		(property "Reference" "C1A8"
			(at 0 0 90)
			(layer "F.SilkS")
			(hide yes)
			(effects
				(font
					(size 1.27 1.27)
				)
			)
		)
		(property "Value" ""
			(at 0 0 90)
			(layer "F.Fab")
			(effects
				(font
					(size 1.27 1.27)
				)
			)
		)
		(duplicate_pad_numbers_are_jumpers no)
		(fp_poly
			(pts
				(xy 0.3048 -0.1016) (xy 0.3048 0.9906) (xy -0.3048 0.9906) (xy -0.3048 -0.1016)
			)
			(stroke
				(width 0)
				(type default)
			)
			(fill no)
			(layer "F.CrtYd")
		)
		(fp_line
			(start 0.3048 -0.1016)
			(end -0.3048 -0.1016)
			(stroke
				(width 0.1)
				(type default)
			)
			(layer "F.Fab")
		)
		(fp_line
			(start -0.3048 -0.1016)
			(end -0.3048 0.9906)
			(stroke
				(width 0.1)
				(type default)
			)
			(layer "F.Fab")
		)
		(fp_line
			(start 0.3048 0.9906)
			(end 0.3048 -0.1016)
			(stroke
				(width 0.1)
				(type default)
			)
			(layer "F.Fab")
		)
		(fp_line
			(start -0.3048 0.9906)
			(end 0.3048 0.9906)
			(stroke
				(width 0.1)
				(type default)
			)
			(layer "F.Fab")
		)
		(pad "1" smd rect
			(at 0 0 90)
			(size 0.508 0.508)
			(layers "F.Cu" "F.Mask" "F.Paste")
			(net "VR_PVDDQ_KLM_PH2_BOOT")
		)
		(pad "2" smd rect
			(at 0 0.889 90)
			(size 0.508 0.508)
			(layers "F.Cu" "F.Mask" "F.Paste")
			(net "VR_PVDDQ_KLM_PH2_PHASE")
		)
		(zone
			(layer "F.Cu")
			(hatch none 0.5)
			(connect_pads
				(clearance 0)
			)
			(min_thickness 0.25)
			(keepout
				(tracks allowed)
				(vias not_allowed)
				(pads allowed)
				(copperpour not_allowed)
				(footprints allowed)
			)
			(placement
				(enabled no)
				(sheetname "")
			)
			(fill
				(thermal_gap 0.5)
				(thermal_bridge_width 0.5)
				(island_removal_mode 0)
			)
			(polygon
				(pts
					(xy -2.602484 -149.03831) (xy -2.602484 -149.54631) (xy -2.221484 -149.54631) (xy -2.221484 -149.03831)
				)
			)
		)
		(zone
			(layer "F.Cu")
			(hatch none 0.5)
			(connect_pads
				(clearance 0)
			)
			(min_thickness 0.25)
			(keepout
				(tracks not_allowed)
				(vias allowed)
				(pads allowed)
				(copperpour not_allowed)
				(footprints allowed)
			)
			(placement
				(enabled no)
				(sheetname "")
			)
			(fill
				(thermal_gap 0.5)
				(thermal_bridge_width 0.5)
				(island_removal_mode 0)
			)
			(polygon
				(pts
					(xy -2.221484 -149.03831) (xy -2.221484 -149.54631) (xy -2.602484 -149.54631) (xy -2.602484 -149.03831)
				)
			)
		)
	)
	(footprint ""
		(layer "F.Cu")
		(at 324.612 -35.052 -90)
		(property "Reference" "R6F3"
			(at 0 0 270)
			(layer "F.SilkS")
			(hide yes)
			(effects
				(font
					(size 1.27 1.27)
				)
			)
		)
		(property "Value" ""
			(at 0 0 270)
			(layer "F.Fab")
			(effects
				(font
					(size 1.27 1.27)
				)
			)
		)
		(duplicate_pad_numbers_are_jumpers no)
		(fp_poly
			(pts
				(xy -0.2794 -0.1016) (xy 0.2794 -0.1016) (xy 0.2794 0.9906) (xy -0.2794 0.9906)
			)
			(stroke
				(width 0)
				(type default)
			)
			(fill no)
			(layer "F.CrtYd")
		)
		(fp_line
			(start -0.2794 0.9906)
			(end 0.2794 0.9906)
			(stroke
				(width 0.1)
				(type default)
			)
			(layer "F.Fab")
		)
		(fp_line
			(start 0.2794 0.9906)
			(end 0.2794 -0.1016)
			(stroke
				(width 0.1)
				(type default)
			)
			(layer "F.Fab")
		)
		(fp_line
			(start -0.2794 -0.1016)
			(end -0.2794 0.9906)
			(stroke
				(width 0.1)
				(type default)
			)
			(layer "F.Fab")
		)
		(fp_line
			(start 0.2794 -0.1016)
			(end -0.2794 -0.1016)
			(stroke
				(width 0.1)
				(type default)
			)
			(layer "F.Fab")
		)
		(pad "1" smd rect
			(at 0 0 270)
			(size 0.508 0.508)
			(layers "F.Cu" "F.Mask" "F.Paste")
			(net "PVPP_ABC")
		)
		(pad "2" smd rect
			(at 0 0.889 270)
			(size 0.508 0.508)
			(layers "F.Cu" "F.Mask" "F.Paste")
			(net "IRQ_DIMM_SAVE_N")
		)
		(zone
			(layer "F.Cu")
			(hatch none 0.5)
			(connect_pads
				(clearance 0)
			)
			(min_thickness 0.25)
			(keepout
				(tracks not_allowed)
				(vias allowed)
				(pads allowed)
				(copperpour not_allowed)
				(footprints allowed)
			)
			(placement
				(enabled no)
				(sheetname "")
			)
			(fill
				(thermal_gap 0.5)
				(thermal_bridge_width 0.5)
				(island_removal_mode 0)
			)
			(polygon
				(pts
					(xy 323.977 -35.306) (xy 323.977 -34.798) (xy 324.358 -34.798) (xy 324.358 -35.306)
				)
			)
		)
		(zone
			(layer "F.Cu")
			(hatch none 0.5)
			(connect_pads
				(clearance 0)
			)
			(min_thickness 0.25)
			(keepout
				(tracks allowed)
				(vias not_allowed)
				(pads allowed)
				(copperpour not_allowed)
				(footprints allowed)
			)
			(placement
				(enabled no)
				(sheetname "")
			)
			(fill
				(thermal_gap 0.5)
				(thermal_bridge_width 0.5)
				(island_removal_mode 0)
			)
			(polygon
				(pts
					(xy 324.358 -35.306) (xy 324.358 -34.798) (xy 323.977 -34.798) (xy 323.977 -35.306)
				)
			)
		)
	)
	(footprint ""
		(layer "F.Cu")
		(at 21.336 -70.866)
		(property "Reference" "C1D27"
			(at 0 0 0)
			(layer "F.SilkS")
			(hide yes)
			(effects
				(font
					(size 1.27 1.27)
				)
			)
		)
		(property "Value" ""
			(at 0 0 0)
			(layer "F.Fab")
			(effects
				(font
					(size 1.27 1.27)
				)
			)
		)
		(duplicate_pad_numbers_are_jumpers no)
		(fp_rect
			(start 0.3048 0.9906)
			(end -0.3048 -0.1016)
			(stroke
				(width 0)
				(type default)
			)
			(fill no)
			(layer "F.CrtYd")
		)
		(fp_line
			(start -0.3048 -0.1016)
			(end -0.3048 0.9906)
			(stroke
				(width 0.1)
				(type default)
			)
			(layer "F.Fab")
		)
		(fp_line
			(start -0.3048 0.9906)
			(end 0.3048 0.9906)
			(stroke
				(width 0.1)
				(type default)
			)
			(layer "F.Fab")
		)
		(fp_line
			(start 0.3048 -0.1016)
			(end -0.3048 -0.1016)
			(stroke
				(width 0.1)
				(type default)
			)
			(layer "F.Fab")
		)
		(fp_line
			(start 0.3048 0.9906)
			(end 0.3048 -0.1016)
			(stroke
				(width 0.1)
				(type default)
			)
			(layer "F.Fab")
		)
		(pad "1" smd rect
			(at 0 0)
			(size 0.508 0.508)
			(layers "F.Cu" "F.Mask" "F.Paste")
			(net "A_HSC_OV")
		)
		(pad "2" smd rect
			(at 0 0.889)
			(size 0.508 0.508)
			(layers "F.Cu" "F.Mask" "F.Paste")
			(net "AGND_HSC")
		)
		(zone
			(layer "F.Cu")
			(hatch none 0.5)
			(connect_pads
				(clearance 0)
			)
			(min_thickness 0.25)
			(keepout
				(tracks not_allowed)
				(vias allowed)
				(pads allowed)
				(copperpour not_allowed)
				(footprints allowed)
			)
			(placement
				(enabled no)
				(sheetname "")
			)
			(fill
				(thermal_gap 0.5)
				(thermal_bridge_width 0.5)
				(island_removal_mode 0)
			)
			(polygon
				(pts
					(xy 21.59 -70.231) (xy 21.59 -70.612) (xy 21.082 -70.612) (xy 21.082 -70.231)
				)
			)
		)
		(zone
			(layer "F.Cu")
			(hatch none 0.5)
			(connect_pads
				(clearance 0)
			)
			(min_thickness 0.25)
			(keepout
				(tracks allowed)
				(vias not_allowed)
				(pads allowed)
				(copperpour not_allowed)
				(footprints allowed)
			)
			(placement
				(enabled no)
				(sheetname "")
			)
			(fill
				(thermal_gap 0.5)
				(thermal_bridge_width 0.5)
				(island_removal_mode 0)
			)
			(polygon
				(pts
					(xy 21.59 -70.231) (xy 21.59 -70.612) (xy 21.082 -70.612) (xy 21.082 -70.231)
				)
			)
		)
	)
	(footprint ""
		(layer "F.Cu")
		(at 30.3276 -69.8754)
		(property "Reference" "CT16"
			(at -0.88773 0.6858 90)
			(unlocked yes)
			(layer "F.SilkS")
			(effects
				(font
					(size 0.7874 0.5842)
					(thickness 0.1524)
				)
				(justify left)
			)
		)
		(property "Value" ""
			(at 0 0 0)
			(layer "F.Fab")
			(effects
				(font
					(size 1.27 1.27)
				)
			)
		)
		(duplicate_pad_numbers_are_jumpers no)
		(fp_poly
			(pts
				(xy 0.3048 -0.1016) (xy 0.3048 0.9906) (xy -0.3048 0.9906) (xy -0.3048 -0.1016)
			)
			(stroke
				(width 0)
				(type default)
			)
			(fill no)
			(layer "F.CrtYd")
		)
		(fp_line
			(start -0.3048 -0.1016)
			(end -0.3048 0.9906)
			(stroke
				(width 0.1)
				(type default)
			)
			(layer "F.Fab")
		)
		(fp_line
			(start -0.3048 0.9906)
			(end 0.3048 0.9906)
			(stroke
				(width 0.1)
				(type default)
			)
			(layer "F.Fab")
		)
		(fp_line
			(start 0.3048 -0.1016)
			(end -0.3048 -0.1016)
			(stroke
				(width 0.1)
				(type default)
			)
			(layer "F.Fab")
		)
		(fp_line
			(start 0.3048 0.9906)
			(end 0.3048 -0.1016)
			(stroke
				(width 0.1)
				(type default)
			)
			(layer "F.Fab")
		)
		(pad "1" smd rect
			(at 0 0)
			(size 0.508 0.508)
			(layers "F.Cu" "F.Mask" "F.Paste")
			(net "VR_PVCCIN_CPU1_AIREF3")
		)
		(pad "2" smd rect
			(at 0 0.889)
			(size 0.508 0.508)
			(layers "F.Cu" "F.Mask" "F.Paste")
			(net "GND")
		)
		(zone
			(layer "F.Cu")
			(hatch none 0.5)
			(connect_pads
				(clearance 0)
			)
			(min_thickness 0.25)
			(keepout
				(tracks allowed)
				(vias not_allowed)
				(pads allowed)
				(copperpour not_allowed)
				(footprints allowed)
			)
			(placement
				(enabled no)
				(sheetname "")
			)
			(fill
				(thermal_gap 0.5)
				(thermal_bridge_width 0.5)
				(island_removal_mode 0)
			)
			(polygon
				(pts
					(xy 30.0736 -69.6214) (xy 30.5816 -69.6214) (xy 30.5816 -69.2404) (xy 30.0736 -69.2404)
				)
			)
		)
		(zone
			(layer "F.Cu")
			(hatch none 0.5)
			(connect_pads
				(clearance 0)
			)
			(min_thickness 0.25)
			(keepout
				(tracks not_allowed)
				(vias allowed)
				(pads allowed)
				(copperpour not_allowed)
				(footprints allowed)
			)
			(placement
				(enabled no)
				(sheetname "")
			)
			(fill
				(thermal_gap 0.5)
				(thermal_bridge_width 0.5)
				(island_removal_mode 0)
			)
			(polygon
				(pts
					(xy 30.0736 -69.2404) (xy 30.5816 -69.2404) (xy 30.5816 -69.6214) (xy 30.0736 -69.6214)
				)
			)
		)
	)
	(footprint ""
		(layer "F.Cu")
		(at 381.508 -88.2015)
		(property "Reference" "R3N26"
			(at 0 0 0)
			(layer "F.SilkS")
			(hide yes)
			(effects
				(font
					(size 1.27 1.27)
				)
			)
		)
		(property "Value" ""
			(at 0 0 0)
			(layer "F.Fab")
			(effects
				(font
					(size 1.27 1.27)
				)
			)
		)
		(duplicate_pad_numbers_are_jumpers no)
		(fp_poly
			(pts
				(xy -0.2794 -0.1016) (xy 0.2794 -0.1016) (xy 0.2794 0.9906) (xy -0.2794 0.9906)
			)
			(stroke
				(width 0)
				(type default)
			)
			(fill no)
			(layer "F.CrtYd")
		)
		(fp_line
			(start -0.2794 -0.1016)
			(end -0.2794 0.9906)
			(stroke
				(width 0.1)
				(type default)
			)
			(layer "F.Fab")
		)
		(fp_line
			(start -0.2794 0.9906)
			(end 0.2794 0.9906)
			(stroke
				(width 0.1)
				(type default)
			)
			(layer "F.Fab")
		)
		(fp_line
			(start 0.2794 -0.1016)
			(end -0.2794 -0.1016)
			(stroke
				(width 0.1)
				(type default)
			)
			(layer "F.Fab")
		)
		(fp_line
			(start 0.2794 0.9906)
			(end 0.2794 -0.1016)
			(stroke
				(width 0.1)
				(type default)
			)
			(layer "F.Fab")
		)
		(pad "1" smd rect
			(at 0 0)
			(size 0.508 0.508)
			(layers "F.Cu" "F.Mask" "F.Paste")
			(net "LPC_LAD0_IO0")
		)
		(pad "2" smd rect
			(at 0 0.889)
			(size 0.508 0.508)
			(layers "F.Cu" "F.Mask" "F.Paste")
			(net "LPC_LAD0_IO0_R")
		)
		(zone
			(layer "F.Cu")
			(hatch none 0.5)
			(connect_pads
				(clearance 0)
			)
			(min_thickness 0.25)
			(keepout
				(tracks allowed)
				(vias not_allowed)
				(pads allowed)
				(copperpour not_allowed)
				(footprints allowed)
			)
			(placement
				(enabled no)
				(sheetname "")
			)
			(fill
				(thermal_gap 0.5)
				(thermal_bridge_width 0.5)
				(island_removal_mode 0)
			)
			(polygon
				(pts
					(xy 381.254 -87.9475) (xy 381.762 -87.9475) (xy 381.762 -87.5665) (xy 381.254 -87.5665)
				)
			)
		)
		(zone
			(layer "F.Cu")
			(hatch none 0.5)
			(connect_pads
				(clearance 0)
			)
			(min_thickness 0.25)
			(keepout
				(tracks not_allowed)
				(vias allowed)
				(pads allowed)
				(copperpour not_allowed)
				(footprints allowed)
			)
			(placement
				(enabled no)
				(sheetname "")
			)
			(fill
				(thermal_gap 0.5)
				(thermal_bridge_width 0.5)
				(island_removal_mode 0)
			)
			(polygon
				(pts
					(xy 381.254 -87.5665) (xy 381.762 -87.5665) (xy 381.762 -87.9475) (xy 381.254 -87.9475)
				)
			)
		)
	)
)
